(kicad_pcb
	(version 20260206)
	(generator "pcbnew")
	(generator_version "10.0")
	(general
		(thickness 1.6)
		(legacy_teardrops no)
	)
	(paper "A4")
	(title_block
		(title "pdpb — Lightning_PDPB_BRD.brd")
		(comment 1 "Lightning (Wiwynn / Facebook NVMe JBOF) / footprints 829-835 of 1140")
	)
	(layers
		(0 "F.Cu" signal "TOP")
		(4 "In1.Cu" signal "L2GND")
		(6 "In2.Cu" signal "L3")
		(8 "In3.Cu" signal "L4VCC")
		(10 "In4.Cu" signal "L5VCC")
		(12 "In5.Cu" signal "L6")
		(14 "In6.Cu" signal "L7GND")
		(2 "B.Cu" signal "BOTTOM")
		(9 "F.Adhes" user "F.Adhesive")
		(11 "B.Adhes" user "B.Adhesive")
		(13 "F.Paste" user "Package Geometry/Pastemask Top")
		(15 "B.Paste" user "Package Geometry/Pastemask Bottom")
		(5 "F.SilkS" user "Ref Des/Silkscreen Top")
		(7 "B.SilkS" user "Ref Des/Silkscreen Bottom")
		(1 "F.Mask" user "Board Geometry/Soldermask Top")
		(3 "B.Mask" user "Board Geometry/Soldermask Bottom")
		(17 "Dwgs.User" user "User.Drawings")
		(19 "Cmts.User" user "User.Comments")
		(21 "Eco1.User" user "User.Eco1")
		(23 "Eco2.User" user "User.Eco2")
		(25 "Edge.Cuts" user "Board Geometry/Outline")
		(27 "Margin" user)
		(31 "F.CrtYd" user "Package Geometry/Place Bound Top")
		(29 "B.CrtYd" user "Package Geometry/Place Bound Bottom")
		(35 "F.Fab" user "Ref Des/Assembly Top")
		(33 "B.Fab" user "Ref Des/Assembly Bottom")
	)
	(footprint ""
		(layer "F.Cu")
		(at 230.632 -346.198952 -90)
		(property "Reference" "R9789"
			(at 0 0 270)
			(layer "F.SilkS")
			(hide yes)
			(effects
				(font
					(size 1.27 1.27)
				)
			)
		)
		(property "Value" "0R2J-2-GP"
			(at 0.064008 -3.993896 270)
			(unlocked yes)
			(layer "F.Fab")
			(hide yes)
			(effects
				(font
					(size 1.016 1.016)
					(thickness 0.1524)
				)
			)
		)
		(property "Device Type" "R402H16"
			(at 0.064008 -5.517896 270)
			(unlocked yes)
			(layer "F.Fab")
			(hide yes)
			(effects
				(font
					(size 1.016 1.016)
					(thickness 0.1524)
				)
			)
		)
		(duplicate_pad_numbers_are_jumpers no)
		(fp_line
			(start -0.508 -0.9398)
			(end -0.508 0.9398)
			(stroke
				(width 0.1524)
				(type default)
			)
			(layer "F.SilkS")
		)
		(fp_line
			(start 0.508 -0.9398)
			(end -0.508 -0.9398)
			(stroke
				(width 0.1524)
				(type default)
			)
			(layer "F.SilkS")
		)
		(fp_rect
			(start -0.508 0.9398)
			(end 0.508 -0.9398)
			(stroke
				(width 0)
				(type default)
			)
			(fill no)
			(layer "F.CrtYd")
		)
		(fp_rect
			(start -0.508 0.9398)
			(end 0.508 -0.9398)
			(stroke
				(width 0)
				(type default)
			)
			(fill no)
			(layer "F.Fab")
		)
		(pad "1" smd custom
			(at 0 -0.4445 270)
			(size 0.1397 0.1397)
			(layers "F.Cu" "F.Mask" "F.Paste")
			(net "SSD_ACT_DR1_R")
			(options
				(clearance outline)
				(anchor circle)
			)
			(primitives
				(gr_poly
					(pts
						(arc
							(start -0.1778 -0.2794)
							(mid -0.249642 -0.249642)
							(end -0.2794 -0.1778)
						)
						(arc
							(start -0.2794 0.1778)
							(mid -0.249642 0.249642)
							(end -0.1778 0.2794)
						)
						(arc
							(start 0.1778 0.2794)
							(mid 0.249642 0.249642)
							(end 0.2794 0.1778)
						)
						(arc
							(start 0.2794 -0.1778)
							(mid 0.249642 -0.249642)
							(end 0.1778 -0.2794)
						)
					)
					(width 0)
					(fill yes)
				)
			)
		)
		(pad "2" smd custom
			(at 0 0.4445 270)
			(size 0.1397 0.1397)
			(layers "F.Cu" "F.Mask" "F.Paste")
			(net "SSD_ACT_DR1")
			(options
				(clearance outline)
				(anchor circle)
			)
			(primitives
				(gr_poly
					(pts
						(arc
							(start -0.1778 -0.2794)
							(mid -0.249642 -0.249642)
							(end -0.2794 -0.1778)
						)
						(arc
							(start -0.2794 0.1778)
							(mid -0.249642 0.249642)
							(end -0.1778 0.2794)
						)
						(arc
							(start 0.1778 0.2794)
							(mid 0.249642 0.249642)
							(end 0.2794 0.1778)
						)
						(arc
							(start 0.2794 -0.1778)
							(mid 0.249642 -0.249642)
							(end 0.1778 -0.2794)
						)
					)
					(width 0)
					(fill yes)
				)
			)
		)
	)
	(footprint ""
		(layer "F.Cu")
		(at 13.843 -493.776)
		(property "Reference" "D23"
			(at 0 0 0)
			(layer "F.SilkS")
			(hide yes)
			(effects
				(font
					(size 1.27 1.27)
				)
			)
		)
		(property "Value" "RB551V30-1-GP"
			(at 0 -6.7818 0)
			(unlocked yes)
			(layer "F.Fab")
			(hide yes)
			(effects
				(font
					(size 1.016 1.016)
					(thickness 0.1524)
				)
			)
		)
		(property "Device Type" "SOD323AKH44"
			(at 0 -8.6868 0)
			(unlocked yes)
			(layer "F.Fab")
			(hide yes)
			(effects
				(font
					(size 1.016 1.016)
					(thickness 0.1524)
				)
			)
		)
		(duplicate_pad_numbers_are_jumpers no)
		(fp_line
			(start -0.889 -1.9304)
			(end 0.889 -1.9304)
			(stroke
				(width 0.1524)
				(type default)
			)
			(layer "F.SilkS")
		)
		(fp_line
			(start -0.889 2.159)
			(end -0.889 -1.9304)
			(stroke
				(width 0.1524)
				(type default)
			)
			(layer "F.SilkS")
		)
		(fp_line
			(start 0.762 2.0574)
			(end -0.762 2.0574)
			(stroke
				(width 0.508)
				(type default)
			)
			(layer "F.SilkS")
		)
		(fp_line
			(start 0.889 -1.9304)
			(end 0.889 2.159)
			(stroke
				(width 0.1524)
				(type default)
			)
			(layer "F.SilkS")
		)
		(fp_line
			(start 0.889 2.159)
			(end -0.889 2.159)
			(stroke
				(width 0.1524)
				(type default)
			)
			(layer "F.SilkS")
		)
		(fp_rect
			(start -1.016 2.3114)
			(end 1.016 -2.0066)
			(stroke
				(width 0)
				(type default)
			)
			(fill no)
			(layer "F.CrtYd")
		)
		(fp_poly
			(pts
				(xy -1.016 -2.0066) (xy 1.016 -2.0066) (xy 1.016 2.3114) (xy -1.016 2.3114)
			)
			(stroke
				(width 0)
				(type default)
			)
			(fill no)
			(layer "F.Fab")
		)
		(pad "A" smd rect
			(at 0 -1.143)
			(size 0.5588 1.016)
			(layers "F.Cu" "F.Mask" "F.Paste")
			(net "SW_SSD5_R")
		)
		(pad "K" smd rect
			(at 0 1.143)
			(size 0.5588 1.016)
			(layers "F.Cu" "F.Mask" "F.Paste")
			(net "SW_SSD5_N")
		)
	)
	(footprint ""
		(layer "F.Cu")
		(at 27.178 -419.735 180)
		(property "Reference" "PC1180"
			(at 0 0 180)
			(layer "F.SilkS")
			(hide yes)
			(effects
				(font
					(size 1.27 1.27)
				)
			)
		)
		(property "Value" "SC22U25V6KX-GP-U"
			(at -2.860802 -5.279644 180)
			(unlocked yes)
			(layer "F.Fab")
			(hide yes)
			(effects
				(font
					(size 1.016 1.016)
					(thickness 0.1524)
				)
			)
		)
		(property "Device Type" "C1206-TO0D3H75"
			(at -2.860802 -6.803644 180)
			(unlocked yes)
			(layer "F.Fab")
			(hide yes)
			(effects
				(font
					(size 1.016 1.016)
					(thickness 0.1524)
				)
			)
		)
		(duplicate_pad_numbers_are_jumpers no)
		(fp_line
			(start 1.3081 2.3749)
			(end -1.3081 2.3749)
			(stroke
				(width 0.1524)
				(type default)
			)
			(layer "F.SilkS")
		)
		(fp_line
			(start 1.3081 -2.3749)
			(end 1.3081 2.3749)
			(stroke
				(width 0.1524)
				(type default)
			)
			(layer "F.SilkS")
		)
		(fp_line
			(start -1.3081 2.3749)
			(end -1.3081 -2.3749)
			(stroke
				(width 0.1524)
				(type default)
			)
			(layer "F.SilkS")
		)
		(fp_line
			(start -1.3081 -2.3749)
			(end 1.3081 -2.3749)
			(stroke
				(width 0.1524)
				(type default)
			)
			(layer "F.SilkS")
		)
		(fp_rect
			(start -0.8001 1.6002)
			(end 0.8001 -1.6002)
			(stroke
				(width 0)
				(type default)
			)
			(fill no)
			(layer "F.CrtYd")
		)
		(fp_poly
			(pts
				(xy -1.5621 2.4511) (xy -1.5621 1.6002) (xy 0.8001 1.6002) (xy 0.8001 -1.6002) (xy -0.8001 -1.6002)
				(xy -0.8001 1.5875) (xy -1.5621 1.5875) (xy -1.5621 -2.4511) (xy 1.5621 -2.4511) (xy 1.5621 2.4511)
			)
			(stroke
				(width 0)
				(type default)
			)
			(fill no)
			(layer "F.CrtYd")
		)
		(fp_rect
			(start -1.5621 2.4511)
			(end 1.5621 -2.4511)
			(stroke
				(width 0)
				(type default)
			)
			(fill no)
			(layer "F.Fab")
		)
		(pad "1" smd rect
			(at 0 -1.392936 180)
			(size 2.1082 1.4478)
			(layers "F.Cu" "F.Mask" "F.Paste")
			(net "P12V_SSD10")
		)
		(pad "2" smd rect
			(at 0 1.392936 180)
			(size 2.1082 1.4478)
			(layers "F.Cu" "F.Mask" "F.Paste")
			(net "GND")
		)
	)
	(footprint ""
		(layer "F.Cu")
		(at 16.129 -164.332158)
		(property "Reference" "Q93"
			(at 0 0 0)
			(layer "F.SilkS")
			(hide yes)
			(effects
				(font
					(size 1.27 1.27)
				)
			)
		)
		(property "Value" "2N7002A-7-GP"
			(at 0.127 -8.9662 0)
			(unlocked yes)
			(layer "F.Fab")
			(hide yes)
			(effects
				(font
					(size 1.016 1.016)
					(thickness 0.1524)
				)
			)
		)
		(property "Device Type" "SOT23DGS2D4H48"
			(at 0.127 -10.4902 0)
			(unlocked yes)
			(layer "F.Fab")
			(hide yes)
			(effects
				(font
					(size 1.016 1.016)
					(thickness 0.1524)
				)
			)
		)
		(duplicate_pad_numbers_are_jumpers no)
		(fp_line
			(start -1.651 -1.778)
			(end -1.651 1.778)
			(stroke
				(width 0.1524)
				(type default)
			)
			(layer "F.SilkS")
		)
		(fp_line
			(start -1.651 1.778)
			(end 1.651 1.778)
			(stroke
				(width 0.1524)
				(type default)
			)
			(layer "F.SilkS")
		)
		(fp_line
			(start 1.651 -1.778)
			(end -1.651 -1.778)
			(stroke
				(width 0.1524)
				(type default)
			)
			(layer "F.SilkS")
		)
		(fp_line
			(start 1.651 1.778)
			(end 1.651 -1.778)
			(stroke
				(width 0.1524)
				(type default)
			)
			(layer "F.SilkS")
		)
		(fp_poly
			(pts
				(xy -1.778 1.8796) (xy -1.778 -1.8796) (xy 1.778 -1.8796) (xy 1.778 1.8796)
			)
			(stroke
				(width 0)
				(type default)
			)
			(fill no)
			(layer "F.CrtYd")
		)
		(fp_poly
			(pts
				(xy -1.778 1.8796) (xy -1.778 -1.8796) (xy 1.778 -1.8796) (xy 1.778 1.8796)
			)
			(stroke
				(width 0)
				(type default)
			)
			(fill no)
			(layer "F.Fab")
		)
		(pad "D" smd custom
			(at 0 -0.9525)
			(size 0.1905 0.1905)
			(layers "F.Cu" "F.Mask" "F.Paste")
			(net "SSD_ACT_DR13_MOS_N")
			(options
				(clearance outline)
				(anchor circle)
			)
			(primitives
				(gr_poly
					(pts
						(arc
							(start -0.1778 0.5715)
							(mid -0.321484 0.511984)
							(end -0.381 0.3683)
						)
						(arc
							(start -0.381 -0.3683)
							(mid -0.321484 -0.511984)
							(end -0.1778 -0.5715)
						)
						(arc
							(start 0.1778 -0.5715)
							(mid 0.321484 -0.511984)
							(end 0.381 -0.3683)
						)
						(arc
							(start 0.381 0.3683)
							(mid 0.321484 0.511984)
							(end 0.1778 0.5715)
						)
					)
					(width 0)
					(fill yes)
				)
			)
		)
		(pad "G" smd custom
			(at -0.98425 0.9525)
			(size 0.1905 0.1905)
			(layers "F.Cu" "F.Mask" "F.Paste")
			(net "ATTN_LED_DR13_AND_R")
			(options
				(clearance outline)
				(anchor circle)
			)
			(primitives
				(gr_poly
					(pts
						(arc
							(start -0.1778 0.5715)
							(mid -0.321484 0.511984)
							(end -0.381 0.3683)
						)
						(arc
							(start -0.381 -0.3683)
							(mid -0.321484 -0.511984)
							(end -0.1778 -0.5715)
						)
						(arc
							(start 0.1778 -0.5715)
							(mid 0.321484 -0.511984)
							(end 0.381 -0.3683)
						)
						(arc
							(start 0.381 0.3683)
							(mid 0.321484 0.511984)
							(end 0.1778 0.5715)
						)
					)
					(width 0)
					(fill yes)
				)
			)
		)
		(pad "S" smd custom
			(at 0.98425 0.9525)
			(size 0.1905 0.1905)
			(layers "F.Cu" "F.Mask" "F.Paste")
			(net "SSD_ACT_DR13_R")
			(options
				(clearance outline)
				(anchor circle)
			)
			(primitives
				(gr_poly
					(pts
						(arc
							(start -0.1778 0.5715)
							(mid -0.321484 0.511984)
							(end -0.381 0.3683)
						)
						(arc
							(start -0.381 -0.3683)
							(mid -0.321484 -0.511984)
							(end -0.1778 -0.5715)
						)
						(arc
							(start 0.1778 -0.5715)
							(mid 0.321484 -0.511984)
							(end 0.381 -0.3683)
						)
						(arc
							(start 0.381 0.3683)
							(mid 0.321484 0.511984)
							(end 0.1778 0.5715)
						)
					)
					(width 0)
					(fill yes)
				)
			)
		)
	)
	(footprint ""
		(layer "F.Cu")
		(at 224.964752 -346.7608 90)
		(property "Reference" "R9788"
			(at 0 0 90)
			(layer "F.SilkS")
			(hide yes)
			(effects
				(font
					(size 1.27 1.27)
				)
			)
		)
		(property "Value" "0R2J-2-GP"
			(at 0.064008 -3.993896 90)
			(unlocked yes)
			(layer "F.Fab")
			(hide yes)
			(effects
				(font
					(size 1.016 1.016)
					(thickness 0.1524)
				)
			)
		)
		(property "Device Type" "R402H16"
			(at 0.064008 -5.517896 90)
			(unlocked yes)
			(layer "F.Fab")
			(hide yes)
			(effects
				(font
					(size 1.016 1.016)
					(thickness 0.1524)
				)
			)
		)
		(duplicate_pad_numbers_are_jumpers no)
		(fp_line
			(start 0.508 -0.9398)
			(end -0.508 -0.9398)
			(stroke
				(width 0.1524)
				(type default)
			)
			(layer "F.SilkS")
		)
		(fp_line
			(start -0.508 -0.9398)
			(end -0.508 0.9398)
			(stroke
				(width 0.1524)
				(type default)
			)
			(layer "F.SilkS")
		)
		(fp_rect
			(start -0.508 0.9398)
			(end 0.508 -0.9398)
			(stroke
				(width 0)
				(type default)
			)
			(fill no)
			(layer "F.CrtYd")
		)
		(fp_rect
			(start -0.508 0.9398)
			(end 0.508 -0.9398)
			(stroke
				(width 0)
				(type default)
			)
			(fill no)
			(layer "F.Fab")
		)
		(pad "1" smd custom
			(at 0 -0.4445 90)
			(size 0.1397 0.1397)
			(layers "F.Cu" "F.Mask" "F.Paste")
			(net "ATTN_LED_DR1_R")
			(options
				(clearance outline)
				(anchor circle)
			)
			(primitives
				(gr_poly
					(pts
						(arc
							(start -0.1778 -0.2794)
							(mid -0.249642 -0.249642)
							(end -0.2794 -0.1778)
						)
						(arc
							(start -0.2794 0.1778)
							(mid -0.249642 0.249642)
							(end -0.1778 0.2794)
						)
						(arc
							(start 0.1778 0.2794)
							(mid 0.249642 0.249642)
							(end 0.2794 0.1778)
						)
						(arc
							(start 0.2794 -0.1778)
							(mid 0.249642 -0.249642)
							(end 0.1778 -0.2794)
						)
					)
					(width 0)
					(fill yes)
				)
			)
		)
		(pad "2" smd custom
			(at 0 0.4445 90)
			(size 0.1397 0.1397)
			(layers "F.Cu" "F.Mask" "F.Paste")
			(net "ATTN_LED_DR1_N")
			(options
				(clearance outline)
				(anchor circle)
			)
			(primitives
				(gr_poly
					(pts
						(arc
							(start -0.1778 -0.2794)
							(mid -0.249642 -0.249642)
							(end -0.2794 -0.1778)
						)
						(arc
							(start -0.2794 0.1778)
							(mid -0.249642 0.249642)
							(end -0.1778 0.2794)
						)
						(arc
							(start 0.1778 0.2794)
							(mid 0.249642 0.249642)
							(end 0.2794 0.1778)
						)
						(arc
							(start 0.2794 -0.1778)
							(mid 0.249642 -0.249642)
							(end 0.1778 -0.2794)
						)
					)
					(width 0)
					(fill yes)
				)
			)
		)
	)
	(footprint ""
		(layer "F.Cu")
		(at 88.011 -416.814 -90)
		(property "Reference" "R123"
			(at 0 0 270)
			(layer "F.SilkS")
			(hide yes)
			(effects
				(font
					(size 1.27 1.27)
				)
			)
		)
		(property "Value" "4K7R2J-2-GP"
			(at 0.064008 -3.993896 270)
			(unlocked yes)
			(layer "F.Fab")
			(hide yes)
			(effects
				(font
					(size 1.016 1.016)
					(thickness 0.1524)
				)
			)
		)
		(property "Device Type" "R402H16"
			(at 0.064008 -5.517896 270)
			(unlocked yes)
			(layer "F.Fab")
			(hide yes)
			(effects
				(font
					(size 1.016 1.016)
					(thickness 0.1524)
				)
			)
		)
		(duplicate_pad_numbers_are_jumpers no)
		(fp_line
			(start -0.508 -0.9398)
			(end -0.508 0.9398)
			(stroke
				(width 0.1524)
				(type default)
			)
			(layer "F.SilkS")
		)
		(fp_line
			(start 0.508 -0.9398)
			(end -0.508 -0.9398)
			(stroke
				(width 0.1524)
				(type default)
			)
			(layer "F.SilkS")
		)
		(fp_rect
			(start -0.508 0.9398)
			(end 0.508 -0.9398)
			(stroke
				(width 0)
				(type default)
			)
			(fill no)
			(layer "F.CrtYd")
		)
		(fp_rect
			(start -0.508 0.9398)
			(end 0.508 -0.9398)
			(stroke
				(width 0)
				(type default)
			)
			(fill no)
			(layer "F.Fab")
		)
		(pad "1" smd custom
			(at 0 -0.4445 270)
			(size 0.1397 0.1397)
			(layers "F.Cu" "F.Mask" "F.Paste")
			(net "P3V3")
			(options
				(clearance outline)
				(anchor circle)
			)
			(primitives
				(gr_poly
					(pts
						(arc
							(start -0.1778 -0.2794)
							(mid -0.249642 -0.249642)
							(end -0.2794 -0.1778)
						)
						(arc
							(start -0.2794 0.1778)
							(mid -0.249642 0.249642)
							(end -0.1778 0.2794)
						)
						(arc
							(start 0.1778 0.2794)
							(mid 0.249642 0.249642)
							(end 0.2794 0.1778)
						)
						(arc
							(start 0.2794 -0.1778)
							(mid 0.249642 -0.249642)
							(end 0.1778 -0.2794)
						)
					)
					(width 0)
					(fill yes)
				)
			)
		)
		(pad "2" smd custom
			(at 0 0.4445 270)
			(size 0.1397 0.1397)
			(layers "F.Cu" "F.Mask" "F.Paste")
			(net "SSD_PRSNT_NET10")
			(options
				(clearance outline)
				(anchor circle)
			)
			(primitives
				(gr_poly
					(pts
						(arc
							(start -0.1778 -0.2794)
							(mid -0.249642 -0.249642)
							(end -0.2794 -0.1778)
						)
						(arc
							(start -0.2794 0.1778)
							(mid -0.249642 0.249642)
							(end -0.1778 0.2794)
						)
						(arc
							(start 0.1778 0.2794)
							(mid 0.249642 0.249642)
							(end 0.2794 0.1778)
						)
						(arc
							(start 0.2794 -0.1778)
							(mid 0.249642 -0.249642)
							(end 0.1778 -0.2794)
						)
					)
					(width 0)
					(fill yes)
				)
			)
		)
	)
	(footprint ""
		(layer "F.Cu")
		(at 79.121 -437.4134 90)
		(property "Reference" "FB6"
			(at 0 0 90)
			(layer "F.SilkS")
			(hide yes)
			(effects
				(font
					(size 1.27 1.27)
				)
			)
		)
		(property "Value" "BLM21PG331SN1D-2-GP"
			(at 0 -4.2418 90)
			(unlocked yes)
			(layer "F.Fab")
			(hide yes)
			(effects
				(font
					(size 1.016 1.016)
					(thickness 0.1524)
				)
			)
		)
		(property "Device Type" "L805H42"
			(at 0 -5.7912 90)
			(unlocked yes)
			(layer "F.Fab")
			(hide yes)
			(effects
				(font
					(size 1.016 1.016)
					(thickness 0.1524)
				)
			)
		)
		(duplicate_pad_numbers_are_jumpers no)
		(fp_line
			(start 0.889 -1.7018)
			(end 0.889 1.7018)
			(stroke
				(width 0.1524)
				(type default)
			)
			(layer "F.SilkS")
		)
		(fp_line
			(start -0.889 -1.7018)
			(end 0.889 -1.7018)
			(stroke
				(width 0.1524)
				(type default)
			)
			(layer "F.SilkS")
		)
		(fp_line
			(start 0.889 1.7018)
			(end -0.889 1.7018)
			(stroke
				(width 0.1524)
				(type default)
			)
			(layer "F.SilkS")
		)
		(fp_line
			(start -0.889 1.7018)
			(end -0.889 -1.7018)
			(stroke
				(width 0.1524)
				(type default)
			)
			(layer "F.SilkS")
		)
		(fp_rect
			(start -0.9652 1.778)
			(end 0.9652 -1.778)
			(stroke
				(width 0)
				(type default)
			)
			(fill no)
			(layer "F.CrtYd")
		)
		(fp_rect
			(start -0.9652 1.778)
			(end 0.9652 -1.778)
			(stroke
				(width 0)
				(type default)
			)
			(fill no)
			(layer "F.Fab")
		)
		(pad "1" smd rect
			(at 0 -0.9652 90)
			(size 1.397 1.143)
			(layers "F.Cu" "F.Mask" "F.Paste")
			(net "P3V3")
		)
		(pad "2" smd rect
			(at 0 0.9652 90)
			(size 1.397 1.143)
			(layers "F.Cu" "F.Mask" "F.Paste")
			(net "VDD_DIFF_1")
		)
	)
)
